# T6G (Grand Teton) — schematic parts with pin connectivity, parts 2389–2567 of 8303; source: Cadence DE-HDL packaged netlist (pstxprt.dat, pstxnet.dat, pstchip.dat)

C7014  Q_CAPP  470UF 2.5V 20% SPCAP  pkg SMLF  page 301 : 1 = P0V9_CPU0_RT2_2A ; 2 = GND
C7015  Q_CAPP  470UF 2.5V 20% SPCAP  pkg SMLF  page 301 : 1 = P0V9_CPU0_RT2_2A ; 2 = GND
C7016  Q_CAP  100UF 4V 20% X6S  pkg C0805  page 301 : 1 = P0V9_CPU0_RT2_2A ; 2 = GND
C7017  Q_CAPP  470UF 2.5V 20% SPCAP  pkg SMLF  page 312 : 1 = P0V9_CPU0_RT3_2A ; 2 = GND
C7018  Q_CAPP  470UF 2.5V 20% SPCAP  pkg SMLF  page 312 : 1 = P0V9_CPU0_RT3_2A ; 2 = GND
C7019  Q_CAP  100UF 4V 20% X6S  pkg C0805  page 312 : 1 = P0V9_CPU0_RT3_2A ; 2 = GND
C7020  Q_CAPP  470UF 2.5V 20% SPCAP  pkg SMLF  page 323 : 1 = P0V9_CPU1_RT0_2A ; 2 = GND
C7021  Q_CAPP  470UF 2.5V 20% SPCAP  pkg SMLF  page 323 : 1 = P0V9_CPU1_RT0_2A ; 2 = GND
C7022  Q_CAP  100UF 4V 20% X6S  pkg C0805  page 323 : 1 = P0V9_CPU1_RT0_2A ; 2 = GND
C7023  Q_CAPP  470UF 2.5V 20% SPCAP  pkg SMLF  page 334 : 1 = P0V9_CPU1_RT1_2A ; 2 = GND
C7024  Q_CAPP  470UF 2.5V 20% SPCAP  pkg SMLF  page 334 : 1 = P0V9_CPU1_RT1_2A ; 2 = GND
C7025  Q_CAP  100UF 4V 20% X6S  pkg C0805  page 334 : 1 = P0V9_CPU1_RT1_2A ; 2 = GND
C7026  Q_CAPP  470UF 2.5V 20% SPCAP  pkg SMLF  page 345 : 1 = P0V9_CPU1_RT2_2A ; 2 = GND
C7027  Q_CAPP  470UF 2.5V 20% SPCAP  pkg SMLF  page 345 : 1 = P0V9_CPU1_RT2_2A ; 2 = GND
C7028  Q_CAP  100UF 4V 20% X6S  pkg C0805  page 345 : 1 = P0V9_CPU1_RT2_2A ; 2 = GND
C7029  Q_CAPP  470UF 2.5V 20% SPCAP  pkg SMLF  page 356 : 1 = P0V9_CPU1_RT3_2A ; 2 = GND
C7030  Q_CAPP  470UF 2.5V 20% SPCAP  pkg SMLF  page 356 : 1 = P0V9_CPU1_RT3_2A ; 2 = GND
C7031  Q_CAP  100UF 4V 20% X6S  pkg C0805  page 356 : 1 = P0V9_CPU1_RT3_2A ; 2 = GND
C7032  Q_CAPP  470UF 2.5V 20% SPCAP  pkg SMLF  page 279 : 1 = P0V9_CPU0_RT_2D ; 2 = GND
C7033  Q_CAP  47UF 4V 20% X6S  pkg C0805  page 279 : 1 = P0V9_CPU0_RT_2D ; 2 = GND
C7034  Q_CAP  47UF 4V 20% X6S  pkg C0805  page 279 : 1 = P0V9_CPU0_RT_2D ; 2 = GND
C7035  Q_CAP  47UF 4V 20% X6S  pkg C0805  page 279 : 1 = P0V9_CPU0_RT_2D ; 2 = GND
C7036  Q_CAP  47UF 4V 20% X6S  pkg C0805  page 279 : 1 = P0V9_CPU0_RT_2D ; 2 = GND
C7037  Q_CAPP  470UF 2.5V 20% SPCAP  pkg SMLF  page 345 : 1 = P0V9_CPU1_RT_2D ; 2 = GND
C7038  Q_CAP  47UF 4V 20% X6S  pkg C0805  page 345 : 1 = P0V9_CPU1_RT_2D ; 2 = GND
C7039  Q_CAP  47UF 4V 20% X6S  pkg C0805  page 345 : 1 = P0V9_CPU1_RT_2D ; 2 = GND
C7040  Q_CAP  47UF 4V 20% X6S  pkg C0805  page 345 : 1 = P0V9_CPU1_RT_2D ; 2 = GND
C7041  Q_CAP  47UF 4V 20% X6S  pkg C0805  page 345 : 1 = P0V9_CPU1_RT_2D ; 2 = GND
C7500  Q_CAP  0.1UF 10V 10% X7S  pkg C0201  page 184 : 1 = P1V8_AUX ; 2 = GND
C7501  Q_CAP  0.1UF 10V 10% X7S  pkg C0201  page 322 : 1 = P1V8_CPU1_RT_1D ; 2 = GND
C7502  Q_CAP  0.1UF 10V 10% X7S  pkg C0201  page 333 : 1 = P1V8_CPU1_RT_1D ; 2 = GND
C7503  Q_CAP  0.1UF 10V 10% X7S  pkg C0201  page 344 : 1 = P1V8_CPU1_RT_1D ; 2 = GND
C7504  Q_CAP  0.1UF 10V 10% X7S  pkg C0201  page 355 : 1 = P1V8_CPU1_RT_1D ; 2 = GND
C7510  Q_CAP  0.1UF 10V 10% X7S  pkg C0201  page 278 : 1 = P1V8_CPU0_RT_1D ; 2 = GND
C8000  Q_CAP  1000PF 50V 5% EMPTY  pkg 0402  page 123 : 1 = PRSNT_SWB_ISO_N ; 2 = GND
C8001  Q_CAP  0.1UF 25V 10% EMPTY  pkg 0402  page 143 : 1 = OCP_SFF_PRSNT01_R1_N ; 2 = GND
C8002  Q_CAP  0.1UF 25V 10% EMPTY  pkg 0402  page 143 : 1 = OCP_SFF_PRSNT23_R1_N ; 2 = GND
C8003  Q_CAP  0.1UF 25V 10% EMPTY  pkg 0402  page 143 : 1 = OCP_V3_2_PRSNT01_R1_N ; 2 = GND
C8004  Q_CAP  0.1UF 25V 10% EMPTY  pkg 0402  page 143 : 1 = OCP_V3_2_PRSNT23_R1_N ; 2 = GND
C8005  Q_CAP  0.1UF 25V 10% X7R  pkg 0402  page 85 : 1 = PWRGD_P5V_AUX_R3 ; 2 = GND
C8006  Q_CAP  0.1UF 25V 10% X7R  pkg 0402  page 172 : 1 = JTAG_BMC_R_D_OE ; 2 = GND
C8007  Q_CAP  0.1UF 25V 10% X7R  pkg 0402  page 153 : 1 = P1V8_AUX ; 2 = GND
C8008  Q_CAP  0.1UF 25V 10% X7R  pkg 0402  page 136 : 1 = P3V3_OCP_SFF_R ; 2 = GND
C8009  Q_CAP  0.1UF 25V 10% X7R  pkg 0402  page 142 : 1 = P3V3_OCP_V3_2_R ; 2 = GND
C8010  Q_CAP  0.1UF 25V 10% X7R  pkg 0402  page 147 : 1 = P3V3_E1S_0_R ; 2 = GND
C8011  Q_CAP  0.1UF 25V 10% EMPTY  pkg 0402  page 240 : 1 = FM_AC_PWR_BTN_PDB_N ; 2 = GND
C8012  Q_CAP  1UF 25V 10% EMPTY  pkg C0402  page 242 : 1 = FM_AC_PWR_BTN_R_N ; 2 = GND
C8013  Q_CAP  0.1UF 25V 10% EMPTY  pkg 0402  page 242 : 1 = P3V3_AUX ; 2 = GND
C8014  Q_CAP  100NF 50V 10% EMPTY  pkg C0402  page 267 : 1 = OC_P2V5_COMP ; 2 = GND
C8015  Q_CAP  100NF 50V 10% EMPTY  pkg C0402  page 267 : 1 = HSC_OC_VOL ; 2 = GND
C8016  Q_CAP  100NF 50V 10% EMPTY  pkg C0402  page 267 : 1 = P12V_AUX ; 2 = GND
C8017  Q_CAP  100NF 50V 10% EMPTY  pkg C0402  page 268 : 1 = UV_ADR_P2V5_COMP ; 2 = GND
C8018  Q_CAP  100NF 50V 10% EMPTY  pkg C0402  page 268 : 1 = P12V_AUX_UV_ADR_TRIGGER ; 2 = GND
C8019  Q_CAP  100NF 50V 10% X7R  pkg C0402  page 268 : 1 = P12V_AUX ; 2 = GND
C8020  Q_CAP  100NF 50V 10% EMPTY  pkg C0402  page 268 : 1 = UV_P2V5_COMP ; 2 = GND
C8021  Q_CAP  100NF 50V 10% EMPTY  pkg C0402  page 268 : 1 = P12V_AUX_UV_TRIGGER ; 2 = GND
C8022  Q_CAP  100NF 50V 10% X7R  pkg C0402  page 268 : 1 = P12V_AUX ; 2 = GND
C8066  Q_CAP  1000PF 50V 5% X7R  pkg 0402  page 200 : 1 = PVDDIO_P0_EN_R ; 2 = GND
C8069  Q_CAP  1000PF 50V 5% X7R  pkg 0402  page 200 : 1 = PVDDCR_CPU1_P0_EN_R ; 2 = GND
C8070  Q_CAP  1000PF 50V 5% EMPTY  pkg 0402  page 200 : 1 = PWRGD_PVDDCR_CPU1_P0_R ; 2 = GND
C8072  Q_CAP  1000PF 50V 5% EMPTY  pkg 0402  page 200 : 1 = PWRGD_PVDDIO_P0_R ; 2 = GND
C8246  Q_CAP  1000PF 50V 5% EMPTY  pkg 0402  page 210 : 1 = PWRGD_PVDDCR_SOC_P1_R ; 2 = GND
C8356  Q_CAP  1000PF 50V 5% X7R  pkg 0402  page 217 : 1 = PVDDIO_P1_EN_R ; 2 = GND
C8359  Q_CAP  1000PF 50V 5% X7R  pkg 0402  page 217 : 1 = PVDDCR_CPU1_P1_EN_R ; 2 = GND
C8360  Q_CAP  1000PF 50V 5% EMPTY  pkg 0402  page 217 : 1 = PWRGD_PVDDCR_CPU1_P1_R ; 2 = GND
C8362  Q_CAP  1000PF 50V 5% EMPTY  pkg 0402  page 217 : 1 = PWRGD_PVDDIO_P1_R ; 2 = GND
C8641  Q_CAP  1000PF 50V 5% EMPTY  pkg 0402  page 224 : 1 = PWRGD_PVDD11_S3_P1_R ; 2 = GND
C9000  Q_CAP  1000PF 50V 5% EMPTY  pkg 0402  page 123 : 1 = PRSNT_CABLE_SWB_B1_ISO_N ; 2 = GND
C9001  Q_CAP  1000PF 50V 5% EMPTY  pkg 0402  page 123 : 1 = PRSNT_CABLE_SWB_B2_ISO_N ; 2 = GND
C9002  Q_CAP  1000PF 50V 5% EMPTY  pkg 0402  page 123 : 1 = PRSNT_CABLE_GPU_A3_ISO_N ; 2 = GND
C9003  Q_CAP  1UF 25V 10% EMPTY  pkg C0402  page 267 : 1 = U142_VS ; 2 = GND
C9004  Q_CAP  1UF 25V 10% EMPTY  pkg C0402  page 268 : 1 = U206_VS ; 2 = GND
C9005  Q_CAP  0.1UF 25V 10% X7R  pkg 0402  page 85 : 1 = IRQ_HSC_FAULT_BUF_N ; 2 = GND
C9007  Q_CAP  0.1UF 25V 10% X7R  pkg 0402  page 136 : 1 = P3V3_AUX ; 2 = GND
C9008  Q_CAP  0.1UF 25V 10% X7R  pkg 0402  page 136 : 1 = P3V3_AUX ; 2 = GND
C9050  Q_CAP  0.1UF 25V 10% X7R  pkg 0402  page 136 : 1 = P3V3_AUX ; 2 = GND
C9051  Q_CAP  0.1UF 25V 10% X7R  pkg 0402  page 142 : 1 = P3V3_AUX ; 2 = GND
C9102  Q_CAP_DIFFBUS  DIFF BUS_0.22UF 6.3V 20% X6S  pkg C0201  page 67 : 1 = P3E_CPU1_P4_TX_C_DP<1> ; 2 = P3E_CPU1_P4_TX_DP<1>
C9103  Q_CAP_DIFFBUS  DIFF BUS_0.22UF 6.3V 20% X6S  pkg C0201  page 67 : 1 = P3E_CPU1_P4_TX_C_DN<1> ; 2 = P3E_CPU1_P4_TX_DN<1>
C9104  Q_CAP_DIFFBUS  DIFF BUS_0.22UF 6.3V 20% X6S  pkg C0201  page 67 : 1 = P3E_CPU1_P4_TX_C_DP<0> ; 2 = P3E_CPU1_P4_TX_DP<0>
C9105  Q_CAP_DIFFBUS  DIFF BUS_0.22UF 6.3V 20% X6S  pkg C0201  page 67 : 1 = P3E_CPU1_P4_TX_C_DN<0> ; 2 = P3E_CPU1_P4_TX_DN<0>
C9226  Q_CAP  0.22UF 25V 10% X7R  pkg C0402  page 188 : 1 = VR_P5V_EN_D_R ; 2 = GND
C9922  Q_CAP  22UF 6.3V 20% X6S  pkg C0603  page 144 : 1 = P3V3_M2_0 ; 2 = GND
C10179  Q_CAP  22UF 4V 20% X6S  pkg C0402  page 69 : 1 = PVDDCR_CPU0_P0 ; 2 = GND
D1  BAT547F  IC  pkg SOT23_123XB  page 188 : 1 = P3V3 ; 3 = P5V
D5  Q_LED  IC  pkg SMLF  page 166 : A = PU_BOOT_RDY_LED ; C = BOOT_RDY_LED_N
D6  Q_LED  IC  pkg SMLF  page 166 : A = PU_SMERR_LED ; C = SMERR_LED_N
D7  Q_LED  IC  pkg SMLF  page 85 : A = BMC_FPGA_LED2_R_N ; C = BMC_FPGA_LED2_N
D8  Q_LED  IC  pkg SMLF  page 85 : A = BMC_FPGA_LED1_R_N ; C = BMC_FPGA_LED1_N
D9  Q_LED  IC  pkg SMLF  page 165 : A = LED_BIOS_DBG_MODE_R ; C = LED_BIOS_DBG_MODE
D46  Q_LED  IC  pkg SMLF  page 166 : A = PU_P12V_ALL_PWROK_LED ; C = P12V_ALL_PWROK_N
D49  Q_LED  IC  pkg SMLF  page 166 : A = P5V_STBY_PWR_LED ; C = GND
D73  Q_LED  IC  pkg SMLF  page 255 : A = LED_PWRGD_PVDD33_S5_R ; C = LED_PWRGD_PVDD33_S5_D
D74  Q_LED  IC  pkg SMLF  page 255 : A = LED_PWRGD_PVDDCR_CPU0_P0_R ; C = LED_PWRGD_PVDDCR_CPU0_P0_D
D75  Q_LED  IC  pkg SMLF  page 255 : A = LED_PWRGD_PVDDCR_SOC_P0_R ; C = LED_PWRGD_PVDDCR_SOC_P0_D
D76  Q_LED  IC  pkg SMLF  page 255 : A = LED_PWRGD_PVDDCR_CPU1_P0_R ; C = LED_PWRGD_PVDDCR_CPU1_P0_D
D77  Q_LED  IC  pkg SMLF  page 255 : A = LED_PWRGD_PVDDIO_P0_R ; C = LED_PWRGD_PVDDIO_P0_D
D78  Q_LED  IC  pkg SMLF  page 255 : A = LED_PWRGD_PVDD11_S3_P0_R ; C = LED_PWRGD_PVDD11_S3_P0_D
D79  Q_LED  IC  pkg SMLF  page 255 : A = LED_PWRGD_PVDD18_S5_P0_R ; C = LED_PWRGD_PVDD18_S5_P0_D
D80  Q_LED  IC  pkg SMLF  page 256 : A = LED_PWRGD_PVDDCR_CPU0_P1_R ; C = LED_PWRGD_PVDDCR_CPU0_P1_D
D81  Q_LED  IC  pkg SMLF  page 256 : A = LED_PWRGD_PVDDCR_SOC_P1_R ; C = LED_PWRGD_PVDDCR_SOC_P1_D
D82  Q_LED  IC  pkg SMLF  page 256 : A = LED_PWRGD_PVDDCR_CPU1_P1_R ; C = LED_PWRGD_PVDDCR_CPU1_P1_D
D83  Q_LED  IC  pkg SMLF  page 256 : A = LED_PWRGD_PVDDIO_P1_R ; C = LED_PWRGD_PVDDIO_P1_D
D84  Q_LED  IC  pkg SMLF  page 256 : A = LED_PWRGD_PVDD11_S3_P1_R ; C = LED_PWRGD_PVDD11_S3_P1_D
D85  Q_LED  IC  pkg SMLF  page 256 : A = LED_PWRGD_PVDD18_S5_P1_R ; C = LED_PWRGD_PVDD18_S5_P1_D
D88  Q_LED  IC  pkg SMLF  page 254 : A = LED_PWRGD_SYS_PWROK_R ; C = LED_PWRGD_SYS_PWROK_R_D
D91  Q_LED  IC  pkg SMLF  page 254 : A = LED_PWRGD_P1V8_AUX ; C = LED_PWRGD_P1V8_AUX_D
D93  Q_LED  IC  pkg SMLF  page 254 : A = LED_RST_RSMRST_PLD_R_N ; C = LED_RST_RSMRST_PLD_R_N_D
D96  Q_LED  IC  pkg SMLF  page 254 : A = LED_PWRGD_PS_PWROK_PLD ; C = LED_PWRGD_PS_PWROK_PLD_D
D98  Q_LED  IC  pkg SMLF  page 254 : A = LED_P5V ; C = GND
D99  Q_LED  IC  pkg SMLF  page 254 : A = LED_P3V3 ; C = GND
D6000  Q_LED  IC  pkg SMLF  page 254 : A = LED_PWRGD_P1V2_AUX ; C = LED_PWRGD_P1V2_AUX_D
D8000  Q_LED  IC  pkg SMLF  page 256 : A = LED_P12V_AUX_R1 ; C = GND
D8001  Q_LED  IC  pkg SMLF  page 256 : A = LED_P12V_PSU_R1 ; C = GND
D8002  Q_LED  IC  pkg SMLF  page 256 : A = LED_P12V_SCM_FAULT ; C = LED_P12V_SCM_FAULT_D2
D8003  SCHOTTKY_12  B0530WS7F EMPTY  pkg SOD323XB  page 86 : 1 = PWRGD_CHAF_CPU0_R1 ; 2 = P3V3_AUX
D8004  SCHOTTKY_12  B0530WS7F EMPTY  pkg SOD323XB  page 92 : 1 = PWRGD_CHGL_CPU0_R1 ; 2 = P3V3_AUX
D8005  SCHOTTKY_12  B0530WS7F EMPTY  pkg SOD323XB  page 98 : 1 = PWRGD_CHAF_CPU1_R1 ; 2 = P3V3_AUX
D8006  SCHOTTKY_12  B0530WS7F EMPTY  pkg SOD323XB  page 104 : 1 = PWRGD_CHGL_CPU1_R1 ; 2 = P3V3_AUX

DB1  TDR_3P  EMPTY  pkg TH2  page 260
  1  GND  UNSPEC  = T1_GND
  2  IO1  UNSPEC  = TDR_SE_45_OHM_TOP
  3  IO2  UNSPEC  = TDR_SE_45_OHM_TOP

DB2  TDR_3P  EMPTY  pkg TH2  page 260
  1  GND  UNSPEC  = T1_GND
  2  IO1  UNSPEC  = TDR_SE_45_OHM_IN1
  3  IO2  UNSPEC  = TDR_SE_45_OHM_IN1

DB3  TDR_3P  EMPTY  pkg TH2  page 260
  1  GND  UNSPEC  = T1_GND
  2  IO1  UNSPEC  = TDR_SE_45_OHM_IN2
  3  IO2  UNSPEC  = TDR_SE_45_OHM_IN2

DB4  TDR_3P  EMPTY  pkg TH2  page 260
  1  GND  UNSPEC  = T1_GND
  2  IO1  UNSPEC  = TDR_SE_45_OHM_IN3
  3  IO2  UNSPEC  = TDR_SE_45_OHM_IN3

DB5  TDR_3P  EMPTY  pkg TH2  page 260
  1  GND  UNSPEC  = T1_GND
  2  IO1  UNSPEC  = TDR_SE_45_OHM_IN4
  3  IO2  UNSPEC  = TDR_SE_45_OHM_IN4

DB6  TDR_3P  EMPTY  pkg TH2  page 260
  1  GND  UNSPEC  = T1_GND
  2  IO1  UNSPEC  = TDR_SE_45_OHM_BOT
  3  IO2  UNSPEC  = TDR_SE_45_OHM_BOT

DB7  TDR_3P  EMPTY  pkg TH2  page 260
  1  GND  UNSPEC  = T1_GND
  2  IO1  UNSPEC  = TDR_SE_50_OHM_TOP
  3  IO2  UNSPEC  = TDR_SE_50_OHM_TOP

DB8  TDR_3P  EMPTY  pkg TH2  page 260
  1  GND  UNSPEC  = T1_GND
  2  IO1  UNSPEC  = TDR_SE_50_OHM_IN1
  3  IO2  UNSPEC  = TDR_SE_50_OHM_IN1

DB9  TDR_3P  EMPTY  pkg TH2  page 260
  1  GND  UNSPEC  = T1_GND
  2  IO1  UNSPEC  = TDR_SE_50_OHM_IN2
  3  IO2  UNSPEC  = TDR_SE_50_OHM_IN2

DB10  TDR_3P  EMPTY  pkg TH2  page 260
  1  GND  UNSPEC  = T1_GND
  2  IO1  UNSPEC  = TDR_SE_50_OHM_IN3
  3  IO2  UNSPEC  = TDR_SE_50_OHM_IN3

DB11  TDR_3P  EMPTY  pkg TH2  page 260
  1  GND  UNSPEC  = T1_GND
  2  IO1  UNSPEC  = TDR_SE_50_OHM_IN4
  3  IO2  UNSPEC  = TDR_SE_50_OHM_IN4

DB12  TDR_3P  EMPTY  pkg TH2  page 260
  1  GND  UNSPEC  = T1_GND
  2  IO1  UNSPEC  = TDR_SE_50_OHM_BOT
  3  IO2  UNSPEC  = TDR_SE_50_OHM_BOT

DB13  TDR_3P  EMPTY  pkg TH2  page 260
  1  GND  UNSPEC  = T1_GND
  2  IO1  UNSPEC  = TDR_SE_45_OHM_IN5
  3  IO2  UNSPEC  = TDR_SE_45_OHM_IN5

DB14  TDR_3P  EMPTY  pkg TH2  page 260
  1  GND  UNSPEC  = T1_GND
  2  IO1  UNSPEC  = TDR_SE_45_OHM_IN6
  3  IO2  UNSPEC  = TDR_SE_45_OHM_IN6

DB15  TDR_3P  EMPTY  pkg TH2  page 260
  1  GND  UNSPEC  = T1_GND
  2  IO1  UNSPEC  = TDR_SE_50_OHM_IN5
  3  IO2  UNSPEC  = TDR_SE_50_OHM_IN5

DB16  TDR_3P  EMPTY  pkg TH2  page 260
  1  GND  UNSPEC  = T1_GND
  2  IO1  UNSPEC  = TDR_SE_50_OHM_IN6
  3  IO2  UNSPEC  = TDR_SE_50_OHM_IN6

FS1  Q_FUSE  20A/125V IC  pkg SMLF  page 268 : 1 = P12V_PSU ; 2 = P12V_PSU_FUSE
H2  HOLE  EMPTY  pkg TH  page 230 : 1 = GND
H3  HOLE  EMPTY  pkg TH  page 230 : 1 = GND
H5  HOLE  EMPTY  pkg TH  page 230 : 1 = GND
H8  HOLE  EMPTY  pkg TH  page 230 : 1 = GND
H10  HOLE  EMPTY  pkg TH  page 230 : 1 = GND
H11  HOLE  EMPTY  pkg TH  page 230 : 1 = GND
H12  HOLE  EMPTY  pkg TH  page 230 : 1 = GND
H13  HOLE  EMPTY  pkg TH  page 230 : 1 = GND
H21  HOLE  EMPTY  pkg TH  page 230 : 1 = GND
H22  HOLE  EMPTY  pkg TH  page 230 : 1 = GND
H27  HOLE  EMPTY  pkg TH  page 230 : 1 = NC
H28  HOLE  EMPTY  pkg TH  page 230 : 1 = NC
H29  HOLE  EMPTY  pkg TH  page 230 : 1 = NC
H30  HOLE  EMPTY  pkg TH  page 230 : 1 = NC
H31  HOLE  EMPTY  pkg TH  page 230 : 1 = GND
H32  HOLE  EMPTY  pkg TH  page 230 : 1 = GND
H33  HOLE  EMPTY  pkg TH  page 230 : 1 = GND
H34  HOLE  EMPTY  pkg TH  page 230 : 1 = GND
H37  HOLE  EMPTY  pkg TH  page 230 : 1 = GND
H38  HOLE  EMPTY  pkg TH  page 230 : 1 = GND
H43  HOLE  EMPTY  pkg TH  page 230 : 1 = GND
H44  HOLE  EMPTY  pkg TH  page 230 : 1 = GND
H49  HOLE  EMPTY  pkg TH  page 230 : 1 = GND
H50  HOLE  EMPTY  pkg TH  page 230 : 1 = GND
H53  HOLE  EMPTY  pkg TH  page 230 : 1 = GND
H54  HOLE  EMPTY  pkg TH  page 230 : 1 = GND
H74  HOLE  EMPTY  pkg TH  page 230 : 1 = NC
H75  HOLE  EMPTY  pkg TH  page 230 : 1 = NC
H76  HOLE  EMPTY  pkg TH  page 230 : 1 = GND
H77  HOLE  EMPTY  pkg TH  page 230 : 1 = GND
H86  HOLE  EMPTY  pkg TH  page 230 : 1 = GND
H87  HOLE  EMPTY  pkg TH  page 230 : 1 = GND
H88  HOLE  EMPTY  pkg TH  page 230 : 1 = GND
H89  HOLE  EMPTY  pkg TH  page 230 : 1 = GND
H90  HOLE  EMPTY  pkg TH  page 230 : 1 = NC
H91  HOLE  EMPTY  pkg TH  page 230 : 1 = GND
H92  HOLE  EMPTY  pkg TH  page 230 : 1 = GND
H93  HOLE  EMPTY  pkg TH  page 230 : 1 = GND
H94  HOLE  EMPTY  pkg TH  page 230 : 1 = GND
H95  HOLE  EMPTY  pkg TH  page 230 : 1 = GND
H96  HOLE  EMPTY  pkg TH  page 230 : 1 = GND
H97  HOLE  EMPTY  pkg TH  page 230 : 1 = GND
H98  HOLE  EMPTY  pkg TH  page 230 : 1 = GND
